# SCM (Grand Teton) — schematic netlist excerpt (pin names and nets, part order shuffled) for the footprints in the layout excerpt that follows; sources: Cadence DE-HDL packaged netlist, KiCad conversion of 12092022_DA0F0TMDCD0_F0T_Management_Board_D_brd_V3_OCP.brd

R414  Q_RES  4.7K 1% EMPTY  pkg 0402LF  page 46 : A = P3V3_AUX ; B = SPI_BMC_TPM_MISO
R822  Q_RES  0 5% CHIP  pkg 0402LF  page 10 : A = FM_PRSNT_1_N ; B = FM_PRSNT_0_R_N

(kicad_pcb
	(version 20260206)
	(generator "pcbnew")
	(generator_version "10.0")
	(general
		(thickness 1.6)
		(legacy_teardrops no)
	)
	(paper "A4")
	(title_block
		(title "12092022_DA0F0TMDCD0_F0T_Management_Board_D_brd_V3_OCP.brd")
		(comment 1 "Grand Teton / footprints 328-329 of 1440")
	)
	(layers
		(0 "F.Cu" signal "TOP")
		(4 "In1.Cu" signal "GND")
		(6 "In2.Cu" signal "IN1")
		(8 "In3.Cu" signal "GND1")
		(10 "In4.Cu" signal "IN2")
		(12 "In5.Cu" signal "VCC")
		(14 "In6.Cu" signal "VCC1")
		(16 "In7.Cu" signal "IN3")
		(18 "In8.Cu" signal "GND2")
		(20 "In9.Cu" signal "IN4")
		(22 "In10.Cu" signal "GND3")
		(2 "B.Cu" signal "BOTTOM")
		(9 "F.Adhes" user "F.Adhesive")
		(11 "B.Adhes" user "B.Adhesive")
		(13 "F.Paste" user "Package Geometry/Pastemask Top")
		(15 "B.Paste" user "Package Geometry/Pastemask Bottom")
		(5 "F.SilkS" user "Ref Des/Silkscreen Top")
		(7 "B.SilkS" user "Ref Des/Silkscreen Bottom")
		(1 "F.Mask" user "Board Geometry/Soldermask Top")
		(3 "B.Mask" user "Board Geometry/Soldermask Bottom")
		(17 "Dwgs.User" user "User.Drawings")
		(19 "Cmts.User" user "User.Comments")
		(21 "Eco1.User" user "User.Eco1")
		(23 "Eco2.User" user "User.Eco2")
		(25 "Edge.Cuts" user "Board Geometry/Outline")
		(27 "Margin" user)
		(31 "F.CrtYd" user "Package Geometry/Place Bound Top")
		(29 "B.CrtYd" user "Package Geometry/Place Bound Bottom")
		(35 "F.Fab" user "Ref Des/Assembly Top")
		(33 "B.Fab" user "Ref Des/Assembly Bottom")
	)
	(footprint ""
		(layer "F.Cu")
		(at 72.1614 -106.2482 90)
		(property "Reference" "R822"
			(at 0 0 90)
			(layer "F.SilkS")
			(hide yes)
			(effects
				(font
					(size 1.27 1.27)
				)
			)
		)
		(property "Value" ""
			(at 0 0 90)
			(layer "F.Fab")
			(effects
				(font
					(size 1.27 1.27)
				)
			)
		)
		(duplicate_pad_numbers_are_jumpers no)
		(fp_line
			(start 0.7874 -0.4064)
			(end 0.7874 0.4064)
			(stroke
				(width 0.1524)
				(type default)
			)
			(layer "F.SilkS")
		)
		(fp_line
			(start -0.7874 -0.4064)
			(end 0.7874 -0.4064)
			(stroke
				(width 0.1524)
				(type default)
			)
			(layer "F.SilkS")
		)
		(fp_line
			(start 0.7874 0.4064)
			(end -0.7874 0.4064)
			(stroke
				(width 0.1524)
				(type default)
			)
			(layer "F.SilkS")
		)
		(fp_line
			(start -0.7874 0.4064)
			(end -0.7874 -0.4064)
			(stroke
				(width 0.1524)
				(type default)
			)
			(layer "F.SilkS")
		)
		(fp_line
			(start -0.12065 -0.305054)
			(end -0.12065 -0.2794)
			(stroke
				(width 0.1)
				(type default)
			)
			(layer "F.Fab")
		)
		(fp_line
			(start -0.67945 -0.305054)
			(end -0.12065 -0.305054)
			(stroke
				(width 0.1)
				(type default)
			)
			(layer "F.Fab")
		)
		(fp_line
			(start 0.67945 -0.3048)
			(end 0.67945 0.3048)
			(stroke
				(width 0.1)
				(type default)
			)
			(layer "F.Fab")
		)
		(fp_line
			(start 0.12065 -0.3048)
			(end 0.67945 -0.3048)
			(stroke
				(width 0.1)
				(type default)
			)
			(layer "F.Fab")
		)
		(fp_line
			(start 0.12065 -0.2794)
			(end 0.12065 -0.3048)
			(stroke
				(width 0.1)
				(type default)
			)
			(layer "F.Fab")
		)
		(fp_line
			(start -0.12065 -0.2794)
			(end 0.12065 -0.2794)
			(stroke
				(width 0.1)
				(type default)
			)
			(layer "F.Fab")
		)
		(fp_line
			(start 0.120396 0.2794)
			(end -0.12065 0.2794)
			(stroke
				(width 0.1)
				(type default)
			)
			(layer "F.Fab")
		)
		(fp_line
			(start -0.12065 0.2794)
			(end -0.12065 0.3048)
			(stroke
				(width 0.1)
				(type default)
			)
			(layer "F.Fab")
		)
		(fp_line
			(start 0.67945 0.3048)
			(end 0.120396 0.3048)
			(stroke
				(width 0.1)
				(type default)
			)
			(layer "F.Fab")
		)
		(fp_line
			(start 0.120396 0.3048)
			(end 0.120396 0.2794)
			(stroke
				(width 0.1)
				(type default)
			)
			(layer "F.Fab")
		)
		(fp_line
			(start -0.12065 0.3048)
			(end -0.67945 0.3048)
			(stroke
				(width 0.1)
				(type default)
			)
			(layer "F.Fab")
		)
		(fp_line
			(start -0.67945 0.3048)
			(end -0.67945 -0.305054)
			(stroke
				(width 0.1)
				(type default)
			)
			(layer "F.Fab")
		)
		(pad "1" smd circle
			(at -0.40005 0 90)
			(size 0 0)
			(layers "F.Cu" "F.Mask" "F.Paste")
			(net "FM_PRSNT_1_N")
		)
		(pad "2" smd circle
			(at 0.40005 0 90)
			(size 0 0)
			(layers "F.Cu" "F.Mask" "F.Paste")
			(net "FM_PRSNT_0_R_N")
		)
	)
	(footprint ""
		(layer "F.Cu")
		(at 84.201 -96.774)
		(property "Reference" "R414"
			(at 0 0 0)
			(layer "F.SilkS")
			(hide yes)
			(effects
				(font
					(size 1.27 1.27)
				)
			)
		)
		(property "Value" ""
			(at 0 0 0)
			(layer "F.Fab")
			(effects
				(font
					(size 1.27 1.27)
				)
			)
		)
		(duplicate_pad_numbers_are_jumpers no)
		(fp_line
			(start -0.7874 -0.4064)
			(end 0.7874 -0.4064)
			(stroke
				(width 0.1524)
				(type default)
			)
			(layer "F.SilkS")
		)
		(fp_line
			(start -0.7874 0.4064)
			(end -0.7874 -0.4064)
			(stroke
				(width 0.1524)
				(type default)
			)
			(layer "F.SilkS")
		)
		(fp_line
			(start 0.7874 -0.4064)
			(end 0.7874 0.4064)
			(stroke
				(width 0.1524)
				(type default)
			)
			(layer "F.SilkS")
		)
		(fp_line
			(start 0.7874 0.4064)
			(end -0.7874 0.4064)
			(stroke
				(width 0.1524)
				(type default)
			)
			(layer "F.SilkS")
		)
		(fp_line
			(start -0.67945 -0.305054)
			(end -0.12065 -0.305054)
			(stroke
				(width 0.1)
				(type default)
			)
			(layer "F.Fab")
		)
		(fp_line
			(start -0.67945 0.3048)
			(end -0.67945 -0.305054)
			(stroke
				(width 0.1)
				(type default)
			)
			(layer "F.Fab")
		)
		(fp_line
			(start -0.12065 -0.305054)
			(end -0.12065 -0.2794)
			(stroke
				(width 0.1)
				(type default)
			)
			(layer "F.Fab")
		)
		(fp_line
			(start -0.12065 -0.2794)
			(end 0.12065 -0.2794)
			(stroke
				(width 0.1)
				(type default)
			)
			(layer "F.Fab")
		)
		(fp_line
			(start -0.12065 0.2794)
			(end -0.12065 0.3048)
			(stroke
				(width 0.1)
				(type default)
			)
			(layer "F.Fab")
		)
		(fp_line
			(start -0.12065 0.3048)
			(end -0.67945 0.3048)
			(stroke
				(width 0.1)
				(type default)
			)
			(layer "F.Fab")
		)
		(fp_line
			(start 0.120396 0.2794)
			(end -0.12065 0.2794)
			(stroke
				(width 0.1)
				(type default)
			)
			(layer "F.Fab")
		)
		(fp_line
			(start 0.120396 0.3048)
			(end 0.120396 0.2794)
			(stroke
				(width 0.1)
				(type default)
			)
			(layer "F.Fab")
		)
		(fp_line
			(start 0.12065 -0.3048)
			(end 0.67945 -0.3048)
			(stroke
				(width 0.1)
				(type default)
			)
			(layer "F.Fab")
		)
		(fp_line
			(start 0.12065 -0.2794)
			(end 0.12065 -0.3048)
			(stroke
				(width 0.1)
				(type default)
			)
			(layer "F.Fab")
		)
		(fp_line
			(start 0.67945 -0.3048)
			(end 0.67945 0.3048)
			(stroke
				(width 0.1)
				(type default)
			)
			(layer "F.Fab")
		)
		(fp_line
			(start 0.67945 0.3048)
			(end 0.120396 0.3048)
			(stroke
				(width 0.1)
				(type default)
			)
			(layer "F.Fab")
		)
		(pad "1" smd circle
			(at -0.40005 0)
			(size 0 0)
			(layers "F.Cu" "F.Mask" "F.Paste")
			(net "P3V3_AUX")
		)
		(pad "2" smd circle
			(at 0.40005 0)
			(size 0 0)
			(layers "F.Cu" "F.Mask" "F.Paste")
			(net "SPI_BMC_TPM_MISO")
		)
	)
)
